# S9S_MB_2U (Grand Teton) — schematic netlist excerpt (pin names and nets, part order shuffled) for the footprints in the layout excerpt that follows; sources: Cadence DE-HDL packaged netlist, KiCad conversion of 03242023_DA0F0TMBIJ0_F0T_Motherboard_J_brd_V01_OCP.brd

R1260  Q_RES  10K 1% EMPTY  pkg 0402LF  page 204 : A = P1V05_PCH_AUX ; B = H_CPU_ERR0_PCH_R_N
PR2106  Q_RES  10K 1% CHIP  pkg 0402LF  page 301 : A = HSC_VDD ; B = HSC_VIN_UVW_N

(kicad_pcb
	(version 20260206)
	(generator "pcbnew")
	(generator_version "10.0")
	(general
		(thickness 1.6)
		(legacy_teardrops no)
	)
	(paper "A4")
	(title_block
		(title "03242023_DA0F0TMBIJ0_F0T_Motherboard_J_brd_V01_OCP.brd")
		(comment 1 "Grand Teton / footprints 5783-5784 of 6105")
	)
	(layers
		(0 "F.Cu" signal "TOP")
		(4 "In1.Cu" signal "GND")
		(6 "In2.Cu" signal "IN1")
		(8 "In3.Cu" signal "GND1")
		(10 "In4.Cu" signal "IN2")
		(12 "In5.Cu" signal "GND2")
		(14 "In6.Cu" signal "IN3")
		(16 "In7.Cu" signal "GND3")
		(18 "In8.Cu" signal "VCC")
		(20 "In9.Cu" signal "VCC1")
		(22 "In10.Cu" signal "GND4")
		(24 "In11.Cu" signal "IN4")
		(26 "In12.Cu" signal "GND5")
		(28 "In13.Cu" signal "IN5")
		(30 "In14.Cu" signal "GND6")
		(32 "In15.Cu" signal "IN6")
		(34 "In16.Cu" signal "GND7")
		(2 "B.Cu" signal "BOTTOM")
		(9 "F.Adhes" user "F.Adhesive")
		(11 "B.Adhes" user "B.Adhesive")
		(13 "F.Paste" user "Package Geometry/Pastemask Top")
		(15 "B.Paste" user "Package Geometry/Pastemask Bottom")
		(5 "F.SilkS" user "Ref Des/Silkscreen Top")
		(7 "B.SilkS" user "Ref Des/Silkscreen Bottom")
		(1 "F.Mask" user "Board Geometry/Soldermask Top")
		(3 "B.Mask" user "Board Geometry/Soldermask Bottom")
		(17 "Dwgs.User" user "User.Drawings")
		(19 "Cmts.User" user "User.Comments")
		(21 "Eco1.User" user "User.Eco1")
		(23 "Eco2.User" user "User.Eco2")
		(25 "Edge.Cuts" user "Board Geometry/Outline")
		(27 "Margin" user)
		(31 "F.CrtYd" user "Package Geometry/Place Bound Top")
		(29 "B.CrtYd" user "Package Geometry/Place Bound Bottom")
		(35 "F.Fab" user "Ref Des/Assembly Top")
		(33 "B.Fab" user "Ref Des/Assembly Bottom")
	)
	(footprint ""
		(layer "B.Cu")
		(at 320.170556 -56.612028 90)
		(property "Reference" "R1260"
			(at 0 0 90)
			(layer "B.SilkS")
			(hide yes)
			(effects
				(font
					(size 1.27 1.27)
				)
				(justify mirror)
			)
		)
		(property "Value" ""
			(at 0 0 90)
			(layer "B.Fab")
			(effects
				(font
					(size 1.27 1.27)
				)
				(justify mirror)
			)
		)
		(duplicate_pad_numbers_are_jumpers no)
		(fp_line
			(start 0.7874 -0.4064)
			(end -0.7874 -0.4064)
			(stroke
				(width 0.1524)
				(type default)
			)
			(layer "B.SilkS")
		)
		(fp_line
			(start -0.7874 -0.4064)
			(end -0.7874 0.4064)
			(stroke
				(width 0.1524)
				(type default)
			)
			(layer "B.SilkS")
		)
		(fp_line
			(start 0.7874 0.4064)
			(end 0.7874 -0.4064)
			(stroke
				(width 0.1524)
				(type default)
			)
			(layer "B.SilkS")
		)
		(fp_line
			(start -0.7874 0.4064)
			(end 0.7874 0.4064)
			(stroke
				(width 0.1524)
				(type default)
			)
			(layer "B.SilkS")
		)
		(fp_line
			(start 0.67945 -0.305054)
			(end 0.12065 -0.305054)
			(stroke
				(width 0.1)
				(type default)
			)
			(layer "B.Fab")
		)
		(fp_line
			(start 0.12065 -0.305054)
			(end 0.12065 -0.2794)
			(stroke
				(width 0.1)
				(type default)
			)
			(layer "B.Fab")
		)
		(fp_line
			(start -0.12065 -0.3048)
			(end -0.67945 -0.3048)
			(stroke
				(width 0.1)
				(type default)
			)
			(layer "B.Fab")
		)
		(fp_line
			(start -0.67945 -0.3048)
			(end -0.67945 0.3048)
			(stroke
				(width 0.1)
				(type default)
			)
			(layer "B.Fab")
		)
		(fp_line
			(start 0.12065 -0.2794)
			(end -0.12065 -0.2794)
			(stroke
				(width 0.1)
				(type default)
			)
			(layer "B.Fab")
		)
		(fp_line
			(start -0.12065 -0.2794)
			(end -0.12065 -0.3048)
			(stroke
				(width 0.1)
				(type default)
			)
			(layer "B.Fab")
		)
		(fp_line
			(start 0.12065 0.2794)
			(end 0.12065 0.3048)
			(stroke
				(width 0.1)
				(type default)
			)
			(layer "B.Fab")
		)
		(fp_line
			(start -0.120396 0.2794)
			(end 0.12065 0.2794)
			(stroke
				(width 0.1)
				(type default)
			)
			(layer "B.Fab")
		)
		(fp_line
			(start 0.67945 0.3048)
			(end 0.67945 -0.305054)
			(stroke
				(width 0.1)
				(type default)
			)
			(layer "B.Fab")
		)
		(fp_line
			(start 0.12065 0.3048)
			(end 0.67945 0.3048)
			(stroke
				(width 0.1)
				(type default)
			)
			(layer "B.Fab")
		)
		(fp_line
			(start -0.120396 0.3048)
			(end -0.120396 0.2794)
			(stroke
				(width 0.1)
				(type default)
			)
			(layer "B.Fab")
		)
		(fp_line
			(start -0.67945 0.3048)
			(end -0.120396 0.3048)
			(stroke
				(width 0.1)
				(type default)
			)
			(layer "B.Fab")
		)
		(pad "1" smd circle
			(at 0.40005 0 270)
			(size 0 0)
			(layers "B.Cu" "B.Mask" "B.Paste")
			(net "P1V05_PCH_AUX")
		)
		(pad "2" smd circle
			(at -0.40005 0 270)
			(size 0 0)
			(layers "B.Cu" "B.Mask" "B.Paste")
			(net "H_CPU_ERR0_PCH_R_N")
		)
	)
	(footprint ""
		(layer "B.Cu")
		(at 179.454048 -405.288242 180)
		(property "Reference" "PR2106"
			(at 0 0 0)
			(layer "B.SilkS")
			(hide yes)
			(effects
				(font
					(size 1.27 1.27)
				)
				(justify mirror)
			)
		)
		(property "Value" ""
			(at 0 0 0)
			(layer "B.Fab")
			(effects
				(font
					(size 1.27 1.27)
				)
				(justify mirror)
			)
		)
		(duplicate_pad_numbers_are_jumpers no)
		(fp_line
			(start 0.7874 0.4064)
			(end 0.7874 -0.4064)
			(stroke
				(width 0.1524)
				(type default)
			)
			(layer "B.SilkS")
		)
		(fp_line
			(start 0.7874 -0.4064)
			(end -0.7874 -0.4064)
			(stroke
				(width 0.1524)
				(type default)
			)
			(layer "B.SilkS")
		)
		(fp_line
			(start -0.7874 0.4064)
			(end 0.7874 0.4064)
			(stroke
				(width 0.1524)
				(type default)
			)
			(layer "B.SilkS")
		)
		(fp_line
			(start -0.7874 -0.4064)
			(end -0.7874 0.4064)
			(stroke
				(width 0.1524)
				(type default)
			)
			(layer "B.SilkS")
		)
		(fp_line
			(start 0.67945 0.3048)
			(end 0.67945 -0.305054)
			(stroke
				(width 0.1)
				(type default)
			)
			(layer "B.Fab")
		)
		(fp_line
			(start 0.67945 -0.305054)
			(end 0.12065 -0.305054)
			(stroke
				(width 0.1)
				(type default)
			)
			(layer "B.Fab")
		)
		(fp_line
			(start 0.12065 0.3048)
			(end 0.67945 0.3048)
			(stroke
				(width 0.1)
				(type default)
			)
			(layer "B.Fab")
		)
		(fp_line
			(start 0.12065 0.2794)
			(end 0.12065 0.3048)
			(stroke
				(width 0.1)
				(type default)
			)
			(layer "B.Fab")
		)
		(fp_line
			(start 0.12065 -0.2794)
			(end -0.12065 -0.2794)
			(stroke
				(width 0.1)
				(type default)
			)
			(layer "B.Fab")
		)
		(fp_line
			(start 0.12065 -0.305054)
			(end 0.12065 -0.2794)
			(stroke
				(width 0.1)
				(type default)
			)
			(layer "B.Fab")
		)
		(fp_line
			(start -0.120396 0.3048)
			(end -0.120396 0.2794)
			(stroke
				(width 0.1)
				(type default)
			)
			(layer "B.Fab")
		)
		(fp_line
			(start -0.120396 0.2794)
			(end 0.12065 0.2794)
			(stroke
				(width 0.1)
				(type default)
			)
			(layer "B.Fab")
		)
		(fp_line
			(start -0.12065 -0.2794)
			(end -0.12065 -0.3048)
			(stroke
				(width 0.1)
				(type default)
			)
			(layer "B.Fab")
		)
		(fp_line
			(start -0.12065 -0.3048)
			(end -0.67945 -0.3048)
			(stroke
				(width 0.1)
				(type default)
			)
			(layer "B.Fab")
		)
		(fp_line
			(start -0.67945 0.3048)
			(end -0.120396 0.3048)
			(stroke
				(width 0.1)
				(type default)
			)
			(layer "B.Fab")
		)
		(fp_line
			(start -0.67945 -0.3048)
			(end -0.67945 0.3048)
			(stroke
				(width 0.1)
				(type default)
			)
			(layer "B.Fab")
		)
		(pad "1" smd circle
			(at 0.40005 0)
			(size 0 0)
			(layers "B.Cu" "B.Mask" "B.Paste")
			(net "HSC_VDD")
		)
		(pad "2" smd circle
			(at -0.40005 0)
			(size 0 0)
			(layers "B.Cu" "B.Mask" "B.Paste")
			(net "HSC_VIN_UVW_N")
		)
	)
)
